# SCM (Grand Teton) — schematic netlist excerpt (pin names and nets, part order shuffled) for the footprints in the layout excerpt that follows; sources: Cadence DE-HDL packaged netlist, KiCad conversion of 12092022_DA0F0TMDCD0_F0T_Management_Board_D_brd_V3_OCP.brd

R386  Q_RES  0 5% CHIP  pkg 0402LF  page 29 : A = USB_FPNL_DP ; B = USB2_01_F_DP
PR498  Q_RES  10K 1% CHIP  pkg 0402LF  page 55 : A = P3V3_AUX ; B = PWRGD_P1V2_AUX_R

(kicad_pcb
	(version 20260206)
	(generator "pcbnew")
	(generator_version "10.0")
	(general
		(thickness 1.6)
		(legacy_teardrops no)
	)
	(paper "A4")
	(title_block
		(title "12092022_DA0F0TMDCD0_F0T_Management_Board_D_brd_V3_OCP.brd")
		(comment 1 "Grand Teton / footprints 418-419 of 1440")
	)
	(layers
		(0 "F.Cu" signal "TOP")
		(4 "In1.Cu" signal "GND")
		(6 "In2.Cu" signal "IN1")
		(8 "In3.Cu" signal "GND1")
		(10 "In4.Cu" signal "IN2")
		(12 "In5.Cu" signal "VCC")
		(14 "In6.Cu" signal "VCC1")
		(16 "In7.Cu" signal "IN3")
		(18 "In8.Cu" signal "GND2")
		(20 "In9.Cu" signal "IN4")
		(22 "In10.Cu" signal "GND3")
		(2 "B.Cu" signal "BOTTOM")
		(9 "F.Adhes" user "F.Adhesive")
		(11 "B.Adhes" user "B.Adhesive")
		(13 "F.Paste" user "Package Geometry/Pastemask Top")
		(15 "B.Paste" user "Package Geometry/Pastemask Bottom")
		(5 "F.SilkS" user "Ref Des/Silkscreen Top")
		(7 "B.SilkS" user "Ref Des/Silkscreen Bottom")
		(1 "F.Mask" user "Board Geometry/Soldermask Top")
		(3 "B.Mask" user "Board Geometry/Soldermask Bottom")
		(17 "Dwgs.User" user "User.Drawings")
		(19 "Cmts.User" user "User.Comments")
		(21 "Eco1.User" user "User.Eco1")
		(23 "Eco2.User" user "User.Eco2")
		(25 "Edge.Cuts" user "Board Geometry/Outline")
		(27 "Margin" user)
		(31 "F.CrtYd" user "Package Geometry/Place Bound Top")
		(29 "B.CrtYd" user "Package Geometry/Place Bound Bottom")
		(35 "F.Fab" user "Ref Des/Assembly Top")
		(33 "B.Fab" user "Ref Des/Assembly Bottom")
	)
	(footprint ""
		(layer "F.Cu")
		(at 85.172296 -74.18959 180)
		(property "Reference" "PR498"
			(at 0 0 180)
			(layer "F.SilkS")
			(hide yes)
			(effects
				(font
					(size 1.27 1.27)
				)
			)
		)
		(property "Value" ""
			(at 0 0 180)
			(layer "F.Fab")
			(effects
				(font
					(size 1.27 1.27)
				)
			)
		)
		(duplicate_pad_numbers_are_jumpers no)
		(fp_line
			(start 0.7874 0.4064)
			(end -0.7874 0.4064)
			(stroke
				(width 0.1524)
				(type default)
			)
			(layer "F.SilkS")
		)
		(fp_line
			(start 0.7874 -0.4064)
			(end 0.7874 0.4064)
			(stroke
				(width 0.1524)
				(type default)
			)
			(layer "F.SilkS")
		)
		(fp_line
			(start -0.7874 0.4064)
			(end -0.7874 -0.4064)
			(stroke
				(width 0.1524)
				(type default)
			)
			(layer "F.SilkS")
		)
		(fp_line
			(start -0.7874 -0.4064)
			(end 0.7874 -0.4064)
			(stroke
				(width 0.1524)
				(type default)
			)
			(layer "F.SilkS")
		)
		(fp_line
			(start 0.67945 0.3048)
			(end 0.120396 0.3048)
			(stroke
				(width 0.1)
				(type default)
			)
			(layer "F.Fab")
		)
		(fp_line
			(start 0.67945 -0.3048)
			(end 0.67945 0.3048)
			(stroke
				(width 0.1)
				(type default)
			)
			(layer "F.Fab")
		)
		(fp_line
			(start 0.12065 -0.2794)
			(end 0.12065 -0.3048)
			(stroke
				(width 0.1)
				(type default)
			)
			(layer "F.Fab")
		)
		(fp_line
			(start 0.12065 -0.3048)
			(end 0.67945 -0.3048)
			(stroke
				(width 0.1)
				(type default)
			)
			(layer "F.Fab")
		)
		(fp_line
			(start 0.120396 0.3048)
			(end 0.120396 0.2794)
			(stroke
				(width 0.1)
				(type default)
			)
			(layer "F.Fab")
		)
		(fp_line
			(start 0.120396 0.2794)
			(end -0.12065 0.2794)
			(stroke
				(width 0.1)
				(type default)
			)
			(layer "F.Fab")
		)
		(fp_line
			(start -0.12065 0.3048)
			(end -0.67945 0.3048)
			(stroke
				(width 0.1)
				(type default)
			)
			(layer "F.Fab")
		)
		(fp_line
			(start -0.12065 0.2794)
			(end -0.12065 0.3048)
			(stroke
				(width 0.1)
				(type default)
			)
			(layer "F.Fab")
		)
		(fp_line
			(start -0.12065 -0.2794)
			(end 0.12065 -0.2794)
			(stroke
				(width 0.1)
				(type default)
			)
			(layer "F.Fab")
		)
		(fp_line
			(start -0.12065 -0.305054)
			(end -0.12065 -0.2794)
			(stroke
				(width 0.1)
				(type default)
			)
			(layer "F.Fab")
		)
		(fp_line
			(start -0.67945 0.3048)
			(end -0.67945 -0.305054)
			(stroke
				(width 0.1)
				(type default)
			)
			(layer "F.Fab")
		)
		(fp_line
			(start -0.67945 -0.305054)
			(end -0.12065 -0.305054)
			(stroke
				(width 0.1)
				(type default)
			)
			(layer "F.Fab")
		)
		(pad "1" smd circle
			(at -0.40005 0 180)
			(size 0 0)
			(layers "F.Cu" "F.Mask" "F.Paste")
			(net "P3V3_AUX")
		)
		(pad "2" smd circle
			(at 0.40005 0 180)
			(size 0 0)
			(layers "F.Cu" "F.Mask" "F.Paste")
			(net "PWRGD_P1V2_AUX_R")
		)
	)
	(footprint ""
		(layer "F.Cu")
		(at 28.270454 -15.992602)
		(property "Reference" "R386"
			(at 0 0 0)
			(layer "F.SilkS")
			(hide yes)
			(effects
				(font
					(size 1.27 1.27)
				)
			)
		)
		(property "Value" ""
			(at 0 0 0)
			(layer "F.Fab")
			(effects
				(font
					(size 1.27 1.27)
				)
			)
		)
		(duplicate_pad_numbers_are_jumpers no)
		(fp_line
			(start -0.7874 -0.4064)
			(end 0.7874 -0.4064)
			(stroke
				(width 0.1524)
				(type default)
			)
			(layer "F.SilkS")
		)
		(fp_line
			(start 0.7874 0.4064)
			(end -0.7874 0.4064)
			(stroke
				(width 0.1524)
				(type default)
			)
			(layer "F.SilkS")
		)
		(fp_line
			(start -0.67945 -0.305054)
			(end -0.12065 -0.305054)
			(stroke
				(width 0.1)
				(type default)
			)
			(layer "F.Fab")
		)
		(fp_line
			(start -0.67945 0.3048)
			(end -0.67945 -0.305054)
			(stroke
				(width 0.1)
				(type default)
			)
			(layer "F.Fab")
		)
		(fp_line
			(start -0.12065 -0.305054)
			(end -0.12065 -0.2794)
			(stroke
				(width 0.1)
				(type default)
			)
			(layer "F.Fab")
		)
		(fp_line
			(start -0.12065 -0.2794)
			(end 0.12065 -0.2794)
			(stroke
				(width 0.1)
				(type default)
			)
			(layer "F.Fab")
		)
		(fp_line
			(start -0.12065 0.2794)
			(end -0.12065 0.3048)
			(stroke
				(width 0.1)
				(type default)
			)
			(layer "F.Fab")
		)
		(fp_line
			(start -0.12065 0.3048)
			(end -0.67945 0.3048)
			(stroke
				(width 0.1)
				(type default)
			)
			(layer "F.Fab")
		)
		(fp_line
			(start 0.120396 0.2794)
			(end -0.12065 0.2794)
			(stroke
				(width 0.1)
				(type default)
			)
			(layer "F.Fab")
		)
		(fp_line
			(start 0.120396 0.3048)
			(end 0.120396 0.2794)
			(stroke
				(width 0.1)
				(type default)
			)
			(layer "F.Fab")
		)
		(fp_line
			(start 0.12065 -0.3048)
			(end 0.67945 -0.3048)
			(stroke
				(width 0.1)
				(type default)
			)
			(layer "F.Fab")
		)
		(fp_line
			(start 0.12065 -0.2794)
			(end 0.12065 -0.3048)
			(stroke
				(width 0.1)
				(type default)
			)
			(layer "F.Fab")
		)
		(fp_line
			(start 0.67945 -0.3048)
			(end 0.67945 0.3048)
			(stroke
				(width 0.1)
				(type default)
			)
			(layer "F.Fab")
		)
		(fp_line
			(start 0.67945 0.3048)
			(end 0.120396 0.3048)
			(stroke
				(width 0.1)
				(type default)
			)
			(layer "F.Fab")
		)
		(pad "1" smd circle
			(at -0.40005 0)
			(size 0 0)
			(layers "F.Cu" "F.Mask" "F.Paste")
			(net "USB_FPNL_DP")
		)
		(pad "2" smd circle
			(at 0.40005 0)
			(size 0 0)
			(layers "F.Cu" "F.Mask" "F.Paste")
			(net "USB2_01_F_DP")
		)
	)
)
